%FSTAX23Y23*%
%MOIN*%
%SFA1B1*%

%IPPOS*%
%ADD13C,0.003940*%
%ADD188C,0.000000*%
%LNtimingcard_pcb-1*%
%LPD*%
G54D13*
X02287Y00293D02*
D01*
X02287Y00295*
X02287Y00298*
X02286Y00301*
X02285Y00303*
X02285Y00306*
X02284Y00308*
X02283Y0031*
X02281Y00313*
X0228Y00315*
X02278Y00317*
X02276Y00319*
X02275Y00321*
X02273Y00322*
X0227Y00324*
X02268Y00325*
X02266Y00326*
X02264Y00327*
X02261Y00328*
X02259Y00329*
X02256Y0033*
X02253Y0033*
X02251Y0033*
X02248*
X02246Y0033*
X02243Y0033*
X0224Y00329*
X02238Y00328*
X02235Y00327*
X02233Y00326*
X02231Y00325*
X02229Y00324*
X02226Y00322*
X02224Y00321*
X02223Y00319*
X02221Y00317*
X02219Y00315*
X02218Y00313*
X02216Y0031*
X02215Y00308*
X02214Y00306*
X02214Y00303*
X02213Y00301*
X02212Y00298*
X02212Y00295*
X02212Y00293*
X01771Y0043D02*
D01*
X01771Y00435*
X0177Y0044*
X0177Y00445*
X01768Y00449*
X01767Y00454*
X01765Y00459*
X01763Y00463*
X0176Y00468*
X01757Y00472*
X01754Y00476*
X01751Y0048*
X01747Y00483*
X01744Y00486*
X01739Y00489*
X01735Y00492*
X01731Y00494*
X01726Y00496*
X01722Y00498*
X01717Y00499*
X01712Y005*
X01707Y00501*
X01702Y00501*
X01697*
X01692Y00501*
X01687Y005*
X01682Y00499*
X01677Y00498*
X01672Y00496*
X01668Y00494*
X01663Y00492*
X01659Y00489*
X01655Y00486*
X01651Y00483*
X01648Y0048*
X01644Y00476*
X01641Y00472*
X01638Y00468*
X01636Y00463*
X01634Y00459*
X01632Y00454*
X0163Y00449*
X01629Y00445*
X01628Y0044*
X01628Y00435*
X01627Y0043*
X02287Y00019D02*
Y00293D01*
X02212Y00019D02*
Y00293D01*
X03102Y0D02*
X03122Y00019D01*
X02287D02*
X02307Y0D01*
X02192D02*
X02212Y00019D01*
X01771D02*
X01791Y0D01*
X03122Y00019D02*
Y00501D01*
X02307Y0D02*
X03102D01*
X01791D02*
X02192D01*
X01771Y00019D02*
Y0043D01*
X01627Y00177D02*
Y0043D01*
X01312Y00177D02*
X01627D01*
X01312D02*
Y00501D01*
X0059D02*
X01312D01*
X0059Y00177D02*
Y00501D01*
X0Y00177D02*
X0059D01*
X0D02*
Y04375D01*
X03122Y00501D02*
X07087D01*
Y04375D02*
Y00501D01*
X0Y04375D02*
X07087D01*
G54D188*
X06188Y038D02*
Y03839D01*
X0605Y038D02*
X06188D01*
X0605D02*
Y03839D01*
X06188*
X06178Y04036D02*
Y04075D01*
X0606Y04036D02*
X06178D01*
X0606D02*
Y04075D01*
X06178*
X05915Y03878D02*
X05954D01*
X05915D02*
Y03997D01*
X05954*
Y03878D02*
Y03997D01*
M02*